# ZAIUS-LV_CARD-EVT1-X00-BOM-X01_20160825.xls — Changelist (bom)
| BOM Change List Date:Wed Aug 24 17:08:12 GMT+08:00 2016 |  |  |  |  |  |  |  |  |  |
| New BOM file : C:\<user>\ZAIUS-LV CARD-EVT-HW-EBOM-X00_20160823-X02_20160824.xls |  |  |  |  |  |  |  |  |  |
| Old BOM file : C:\<user>\ZAIUS-LV CARD-EVT-HW-EBOM-X00_20160808_2nd source-X01_20160811.xls |  |  |  |  |  |  |  |  |  |
| ##### Add Parts |  |  |  |  |  |  |  |  |  |
| Item | Location | Qty | Foxconn P/N | Part Description | Manufacturer Full Name | Manufacturer P/N | RoHS | Sheet |  |
| ##### Remove Parts |  |  |  |  |  |  |  |  |  |
| Item | Location | Qty | Foxconn P/N | Part Description | Manufacturer Full Name | Manufacturer P/N | RoHS | Sheet |  |
| 1 | R1 | 1 | 610107A00-017-G | RES,0 Ohm,+/-5%,1/16W,G,SMD0402 | KOA SPEER ELECTRONICS, INC. | RK73Z1ETTP | N | PWA BOM |  |
|  |  |  | 610107A00-024-G | RES,0 Ohm,+/-5%,1/16W,G,SMD0402 | PANASONIC INDUSTRIAL CO.,LTD. | ERJ2GE0R00X |  | PWA BOM |  |
|  |  |  | 610107A00-029-G | RES,0 Ohm,+/-5%,1/16W,G,SMD0402 | VISHAY ENTER TECHNO LOGY.INC | CRCW04020000Z0ED |  | PWA BOM |  |
| ##### Change Parts |  |  |  |  |  |  |  |  |  |
| Item | Location | Qty | Foxconn P/N | Part Description | Manufacturer Full Name | Manufacturer P/N | RoHS | Sheet | Remark |
| 1 | J1,J2 | 2 | 34131N000-G78-G | CONN,BTB,V/T,0.8mm,8u,G,SMD-80 | FCI CONNECTORS HONGKONG LTD. | 61083-081402LF |  | PWA BOM | In New BOM |
|  | J1,J2 | 2 | 34131FN00-G78-G | CONN,BTB,V/T,0.8mm,8u,G,SMD-80 | FCI CONNECTORS HONGKONG LTD. | 61083-081402PLF |  | PWA BOM | In Old BOM |
| ##### Change Revision |  |  |  |  |  |  |  |  |  |
| Sheet | REV OF BOM | CUSTOMER | CUSTOMER P/N | PWA PN | PWA DESCRIPTION | PWA REV | DATE | Remark |  |
| PWA BOM | X02 | DELL |  | 10035W000-600-G | Peripheral Board,G,Zaius-LV Card | X00 | 8/24/16 | In New BOM |  |
| PWA BOM |  | DELL |  |  |  |  |  | In Old BOM |  |
| OOOOOOOOOOOOOOOOOOOOOOOOOOOOOOOOOOOOOOOOOOOOOOOOOOOOOOOOOOOOOOOOOOOOOOOOOOOOOOOOOOOOOOOOOO | OOOOOOOOOOOOOOOOOOOOOOOOOOOOOOOOOOOOOOOOOOOOOOOOOOOOOOOOOOOOOOOOOOOOOOOOOOOOOOOOOOOOOOOOOO | OOOOOOOOOOOOOOOOOOOOOOOOOOOOOOOOOOOOOOOOOOOOOOOOOOOOOOOOOOOOOOOOOOOOOOOOOOOOOOOOOOOOOOOOOO | OOOOOOOOOOOOOOOOOOOOOOOOOOOOOOOOOOOOOOOOOOOOOOOOOOOOOOOOOOOOOOOOOOOOOOOOOOOOOOOOOOOOOOOOOO | OOOOOOOOOOOOOOOOOOOOOOOOOOOOOOOOOOOOOOOOOOOOOOOOOOOOOOOOOOOOOOOOOOOOOOOOOOOOOOOOOOOOOOOOOO | OOOOOOOOOOOOOOOOOOOOOOOOOOOOOOOOOOOOOOOOOOOOOOOOOOOOOOOOOOOOOOOOOOOOOOOOOOOOOOOOOOOOOOOOOO | OOOOOOOOOOOOOOOOOOOOOOOOOOOOOOOOOOOOOOOOOOOOOOOOOOOOOOOOOOOOOOOOOOOOOOOOOOOOOOOOOOOOOOOOOO | OOOOOOOOOOOOOOOOOOOOOOOOOOOOOOOOOOOOOOOOOOOOOOOOOOOOOOOOOOOOOOOOOOOOOOOOOOOOOOOOOOOOOOOOOO | OOOOOOOOOOOOOOOOOOOOOOOOOOOOOOOOOOOOOOOOOOOOOOOOOOOOOOOOOOOOOOOOOOOOOOOOOOOOOOOOOOOOOOOOOO | OOOOOOOOOOOOOOOOOOOOOOOOOOOOOOOOOOOOOOOOOOOOOOOOOOOOOOOOOOOOOOOOOOOOOOOOOOOOOOOOOOOOOOOOOO |
| Second Source Change |  |  |  |  |  |  |  |  |  |
| Item | Location | Change Type | Foxconn P/N | Part Description | Manufacturer Full Name | Manufacturer P/N | RoHS | Sheet |  |
| OOOOOOOOOOOOOOOOOOOOOOOOOOOOOOOOOOOOOOOOOOOOOOOOOOOOOOOOOOOOOOOOOOOOOOOOOOOOOOOOOOOOOOOOOO | OOOOOOOOOOOOOOOOOOOOOOOOOOOOOOOOOOOOOOOOOOOOOOOOOOOOOOOOOOOOOOOOOOOOOOOOOOOOOOOOOOOOOOOOOO | OOOOOOOOOOOOOOOOOOOOOOOOOOOOOOOOOOOOOOOOOOOOOOOOOOOOOOOOOOOOOOOOOOOOOOOOOOOOOOOOOOOOOOOOOO | OOOOOOOOOOOOOOOOOOOOOOOOOOOOOOOOOOOOOOOOOOOOOOOOOOOOOOOOOOOOOOOOOOOOOOOOOOOOOOOOOOOOOOOOOO | OOOOOOOOOOOOOOOOOOOOOOOOOOOOOOOOOOOOOOOOOOOOOOOOOOOOOOOOOOOOOOOOOOOOOOOOOOOOOOOOOOOOOOOOOO | OOOOOOOOOOOOOOOOOOOOOOOOOOOOOOOOOOOOOOOOOOOOOOOOOOOOOOOOOOOOOOOOOOOOOOOOOOOOOOOOOOOOOOOOOO | OOOOOOOOOOOOOOOOOOOOOOOOOOOOOOOOOOOOOOOOOOOOOOOOOOOOOOOOOOOOOOOOOOOOOOOOOOOOOOOOOOOOOOOOOO | OOOOOOOOOOOOOOOOOOOOOOOOOOOOOOOOOOOOOOOOOOOOOOOOOOOOOOOOOOOOOOOOOOOOOOOOOOOOOOOOOOOOOOOOOO | OOOOOOOOOOOOOOOOOOOOOOOOOOOOOOOOOOOOOOOOOOOOOOOOOOOOOOOOOOOOOOOOOOOOOOOOOOOOOOOOOOOOOOOOOO | OOOOOOOOOOOOOOOOOOOOOOOOOOOOOOOOOOOOOOOOOOOOOOOOOOOOOOOOOOOOOOOOOOOOOOOOOOOOOOOOOOOOOOOOOO |
| Master Materials Change |  |  |  |  |  |  |  |  |  |
| Item | Foxconn P/N | Orig._Usage | New_Usage | Part Description | Manufacturer Full Name | Manufacturer P/N | RoHS | Location | Sheet |
| 1 | 610107A00-017-G | 2 | 1 | RES,0 Ohm,+/-5%,1/16W,G,SMD0402 | KOA SPEER ELECTRONICS, INC. | RK73Z1ETTP | N | (-)R1 | PWA BOM |
|  | 610107A00-024-G |  |  | RES,0 Ohm,+/-5%,1/16W,G,SMD0402 | PANASONIC INDUSTRIAL CO.,LTD. | ERJ2GE0R00X |  |  | PWA BOM |
|  | 610107A00-029-G |  |  | RES,0 Ohm,+/-5%,1/16W,G,SMD0402 | VISHAY ENTER TECHNO LOGY.INC | CRCW04020000Z0ED |  |  | PWA BOM |
| 2 | 34131N000-G78-G | 0 | 2 | CONN,BTB,V/T,0.8mm,8u,G,SMD-80 | FCI CONNECTORS HONGKONG LTD. | 61083-081402LF |  | (+)J1,J2 | PWA BOM |
| 3 | 34131FN00-G78-G | 2 | 0 | CONN,BTB,V/T,0.8mm,8u,G,SMD-80 | FCI CONNECTORS HONGKONG LTD. | 61083-081402PLF |  | (-)J1,J2 | PWA BOM |
| OOOOOOOOOOOOOOOOOOOOOOOOOOOOOOOOOOOOOOOOOOOOOOOOOOOOOOOOOOOOOOOOOOOOOOOOOOOOOOOOOOOOOOOOOO | OOOOOOOOOOOOOOOOOOOOOOOOOOOOOOOOOOOOOOOOOOOOOOOOOOOOOOOOOOOOOOOOOOOOOOOOOOOOOOOOOOOOOOOOOO | OOOOOOOOOOOOOOOOOOOOOOOOOOOOOOOOOOOOOOOOOOOOOOOOOOOOOOOOOOOOOOOOOOOOOOOOOOOOOOOOOOOOOOOOOO | OOOOOOOOOOOOOOOOOOOOOOOOOOOOOOOOOOOOOOOOOOOOOOOOOOOOOOOOOOOOOOOOOOOOOOOOOOOOOOOOOOOOOOOOOO | OOOOOOOOOOOOOOOOOOOOOOOOOOOOOOOOOOOOOOOOOOOOOOOOOOOOOOOOOOOOOOOOOOOOOOOOOOOOOOOOOOOOOOOOOO | OOOOOOOOOOOOOOOOOOOOOOOOOOOOOOOOOOOOOOOOOOOOOOOOOOOOOOOOOOOOOOOOOOOOOOOOOOOOOOOOOOOOOOOOOO | OOOOOOOOOOOOOOOOOOOOOOOOOOOOOOOOOOOOOOOOOOOOOOOOOOOOOOOOOOOOOOOOOOOOOOOOOOOOOOOOOOOOOOOOOO | OOOOOOOOOOOOOOOOOOOOOOOOOOOOOOOOOOOOOOOOOOOOOOOOOOOOOOOOOOOOOOOOOOOOOOOOOOOOOOOOOOOOOOOOOO | OOOOOOOOOOOOOOOOOOOOOOOOOOOOOOOOOOOOOOOOOOOOOOOOOOOOOOOOOOOOOOOOOOOOOOOOOOOOOOOOOOOOOOOOOO |  |
| TLA Parts Change |  |  |  |  |  |  |  |  |  |
| Item | Foxconn P/N | Qty | Part Description | Manufacturer Full Name | Manufacturer P/N | RoHS | Location | Remark |  |
| BOM Change List Date:Fri Aug 26 10:25:55 GMT+08:00 2016 |  |  |  |  |  |  |  |  |  |
| New BOM file : C:\<user>\ZAIUS-LV CARD-EVT1-X00-BOM-X01_20160825.xls |  |  |  |  |  |  |  |  |  |
| Old BOM file : C:\<user>\ZAIUS-LV CARD-EVT-HW-EBOM-X00_20160823-X02_20160824.xls |  |  |  |  |  |  |  |  |  |
| ##### Add Parts |  |  |  |  |  |  |  |  |  |
| Item | Location | Qty | Foxconn P/N | Part Description | Manufacturer Full Name | Manufacturer P/N | RoHS | Sheet |  |
| ##### Remove Parts |  |  |  |  |  |  |  |  |  |
| Item | Location | Qty | Foxconn P/N | Part Description | Manufacturer Full Name | Manufacturer P/N | RoHS | Sheet |  |
| ##### Change Parts |  |  |  |  |  |  |  |  |  |
| Item | Location | Qty | Foxconn P/N | Part Description | Manufacturer Full Name | Manufacturer P/N | RoHS | Sheet | Remark |
| ##### Change Revision |  |  |  |  |  |  |  |  |  |
| Sheet | REV OF BOM | CUSTOMER | CUSTOMER P/N | PWA PN | PWA DESCRIPTION | PWA REV | DATE | Remark |  |
| PWA BOM | X01 | DELL |  | 10035W000-600-G | Peripheral Board,G,Zaius-LV Card | X00 | 8/26/16 | In New BOM |  |
| PWA BOM | X02 | DELL |  | 10035W000-600-G | Peripheral Board,G,Zaius-LV Card | X00 | 8/24/16 | In Old BOM |  |
| OOOOOOOOOOOOOOOOOOOOOOOOOOOOOOOOOOOOOOOOOOOOOOOOOOOOOOOOOOOOOOOOOOOOOOOOOOOOOOOOOOOOOOOOOO | OOOOOOOOOOOOOOOOOOOOOOOOOOOOOOOOOOOOOOOOOOOOOOOOOOOOOOOOOOOOOOOOOOOOOOOOOOOOOOOOOOOOOOOOOO | OOOOOOOOOOOOOOOOOOOOOOOOOOOOOOOOOOOOOOOOOOOOOOOOOOOOOOOOOOOOOOOOOOOOOOOOOOOOOOOOOOOOOOOOOO | OOOOOOOOOOOOOOOOOOOOOOOOOOOOOOOOOOOOOOOOOOOOOOOOOOOOOOOOOOOOOOOOOOOOOOOOOOOOOOOOOOOOOOOOOO | OOOOOOOOOOOOOOOOOOOOOOOOOOOOOOOOOOOOOOOOOOOOOOOOOOOOOOOOOOOOOOOOOOOOOOOOOOOOOOOOOOOOOOOOOO | OOOOOOOOOOOOOOOOOOOOOOOOOOOOOOOOOOOOOOOOOOOOOOOOOOOOOOOOOOOOOOOOOOOOOOOOOOOOOOOOOOOOOOOOOO | OOOOOOOOOOOOOOOOOOOOOOOOOOOOOOOOOOOOOOOOOOOOOOOOOOOOOOOOOOOOOOOOOOOOOOOOOOOOOOOOOOOOOOOOOO | OOOOOOOOOOOOOOOOOOOOOOOOOOOOOOOOOOOOOOOOOOOOOOOOOOOOOOOOOOOOOOOOOOOOOOOOOOOOOOOOOOOOOOOOOO | OOOOOOOOOOOOOOOOOOOOOOOOOOOOOOOOOOOOOOOOOOOOOOOOOOOOOOOOOOOOOOOOOOOOOOOOOOOOOOOOOOOOOOOOOO | OOOOOOOOOOOOOOOOOOOOOOOOOOOOOOOOOOOOOOOOOOOOOOOOOOOOOOOOOOOOOOOOOOOOOOOOOOOOOOOOOOOOOOOOOO |
| Second Source Change |  |  |  |  |  |  |  |  |  |
| Item | Location | Change Type | Foxconn P/N | Part Description | Manufacturer Full Name | Manufacturer P/N | RoHS | Sheet |  |
| OOOOOOOOOOOOOOOOOOOOOOOOOOOOOOOOOOOOOOOOOOOOOOOOOOOOOOOOOOOOOOOOOOOOOOOOOOOOOOOOOOOOOOOOOO | OOOOOOOOOOOOOOOOOOOOOOOOOOOOOOOOOOOOOOOOOOOOOOOOOOOOOOOOOOOOOOOOOOOOOOOOOOOOOOOOOOOOOOOOOO | OOOOOOOOOOOOOOOOOOOOOOOOOOOOOOOOOOOOOOOOOOOOOOOOOOOOOOOOOOOOOOOOOOOOOOOOOOOOOOOOOOOOOOOOOO | OOOOOOOOOOOOOOOOOOOOOOOOOOOOOOOOOOOOOOOOOOOOOOOOOOOOOOOOOOOOOOOOOOOOOOOOOOOOOOOOOOOOOOOOOO | OOOOOOOOOOOOOOOOOOOOOOOOOOOOOOOOOOOOOOOOOOOOOOOOOOOOOOOOOOOOOOOOOOOOOOOOOOOOOOOOOOOOOOOOOO | OOOOOOOOOOOOOOOOOOOOOOOOOOOOOOOOOOOOOOOOOOOOOOOOOOOOOOOOOOOOOOOOOOOOOOOOOOOOOOOOOOOOOOOOOO | OOOOOOOOOOOOOOOOOOOOOOOOOOOOOOOOOOOOOOOOOOOOOOOOOOOOOOOOOOOOOOOOOOOOOOOOOOOOOOOOOOOOOOOOOO | OOOOOOOOOOOOOOOOOOOOOOOOOOOOOOOOOOOOOOOOOOOOOOOOOOOOOOOOOOOOOOOOOOOOOOOOOOOOOOOOOOOOOOOOOO | OOOOOOOOOOOOOOOOOOOOOOOOOOOOOOOOOOOOOOOOOOOOOOOOOOOOOOOOOOOOOOOOOOOOOOOOOOOOOOOOOOOOOOOOOO | OOOOOOOOOOOOOOOOOOOOOOOOOOOOOOOOOOOOOOOOOOOOOOOOOOOOOOOOOOOOOOOOOOOOOOOOOOOOOOOOOOOOOOOOOO |
| Master Materials Change |  |  |  |  |  |  |  |  |  |
| Item | Foxconn P/N | Orig._Usage | New_Usage | Part Description | Manufacturer Full Name | Manufacturer P/N | RoHS | Location | Sheet |
| OOOOOOOOOOOOOOOOOOOOOOOOOOOOOOOOOOOOOOOOOOOOOOOOOOOOOOOOOOOOOOOOOOOOOOOOOOOOOOOOOOOOOOOOOO | OOOOOOOOOOOOOOOOOOOOOOOOOOOOOOOOOOOOOOOOOOOOOOOOOOOOOOOOOOOOOOOOOOOOOOOOOOOOOOOOOOOOOOOOOO | OOOOOOOOOOOOOOOOOOOOOOOOOOOOOOOOOOOOOOOOOOOOOOOOOOOOOOOOOOOOOOOOOOOOOOOOOOOOOOOOOOOOOOOOOO | OOOOOOOOOOOOOOOOOOOOOOOOOOOOOOOOOOOOOOOOOOOOOOOOOOOOOOOOOOOOOOOOOOOOOOOOOOOOOOOOOOOOOOOOOO | OOOOOOOOOOOOOOOOOOOOOOOOOOOOOOOOOOOOOOOOOOOOOOOOOOOOOOOOOOOOOOOOOOOOOOOOOOOOOOOOOOOOOOOOOO | OOOOOOOOOOOOOOOOOOOOOOOOOOOOOOOOOOOOOOOOOOOOOOOOOOOOOOOOOOOOOOOOOOOOOOOOOOOOOOOOOOOOOOOOOO | OOOOOOOOOOOOOOOOOOOOOOOOOOOOOOOOOOOOOOOOOOOOOOOOOOOOOOOOOOOOOOOOOOOOOOOOOOOOOOOOOOOOOOOOOO | OOOOOOOOOOOOOOOOOOOOOOOOOOOOOOOOOOOOOOOOOOOOOOOOOOOOOOOOOOOOOOOOOOOOOOOOOOOOOOOOOOOOOOOOOO | OOOOOOOOOOOOOOOOOOOOOOOOOOOOOOOOOOOOOOOOOOOOOOOOOOOOOOOOOOOOOOOOOOOOOOOOOOOOOOOOOOOOOOOOOO |  |
| TLA Parts Change |  |  |  |  |  |  |  |  |  |
| Item | Foxconn P/N | Qty | Part Description | Manufacturer Full Name | Manufacturer P/N | RoHS | Location | Remark |  |
